# BASEBOARD_FAB2 (Tioga Pass) — schematic netlist excerpt (pin names and nets, part order shuffled) for the footprints in the layout excerpt that follows; sources: Cadence DE-HDL packaged netlist, KiCad conversion of Wiwynn_Tioga_Pass_MB.brd

C5D1  CAP_A  22.0UF 4V 20% X6S  pkg 0603V  page 220 : A = PVDDQ_DEF ; B = GND
R7E2  RES  75 1.0% CHIP  pkg 0402  page 92 : A = PVCCIO_CPU0 ; B = H_CPU0_THERMTRIP_G_N
C8A4  CAP  0.1UF 25V 10% X7R  pkg 0603LF  page 237 : A = P3V3_STBY ; B = GND

(kicad_pcb
	(version 20260206)
	(generator "pcbnew")
	(generator_version "10.0")
	(general
		(thickness 1.6)
		(legacy_teardrops no)
	)
	(paper "A4")
	(title_block
		(title "Wiwynn_Tioga_Pass_MB.brd")
		(comment 1 "Tioga Pass / footprints 111-113 of 4770")
	)
	(layers
		(0 "F.Cu" signal "TOP")
		(4 "In1.Cu" signal "L2GND")
		(6 "In2.Cu" signal "L3")
		(8 "In3.Cu" signal "L4GND")
		(10 "In4.Cu" signal "L5")
		(12 "In5.Cu" signal "L6GND")
		(14 "In6.Cu" signal "L7VCC")
		(16 "In7.Cu" signal "L8VCC")
		(18 "In8.Cu" signal "L9GND")
		(20 "In9.Cu" signal "L10")
		(22 "In10.Cu" signal "L11GND")
		(24 "In11.Cu" signal "L12")
		(26 "In12.Cu" signal "L13GND")
		(2 "B.Cu" signal "BOTTOM")
		(9 "F.Adhes" user "F.Adhesive")
		(11 "B.Adhes" user "B.Adhesive")
		(13 "F.Paste" user "Package Geometry/Pastemask Top")
		(15 "B.Paste" user "Package Geometry/Pastemask Bottom")
		(5 "F.SilkS" user "Ref Des/Silkscreen Top")
		(7 "B.SilkS" user "Ref Des/Silkscreen Bottom")
		(1 "F.Mask" user "Board Geometry/Soldermask Top")
		(3 "B.Mask" user "Board Geometry/Soldermask Bottom")
		(17 "Dwgs.User" user "User.Drawings")
		(19 "Cmts.User" user "User.Comments")
		(21 "Eco1.User" user "User.Eco1")
		(23 "Eco2.User" user "User.Eco2")
		(25 "Edge.Cuts" user "Board Geometry/Outline")
		(27 "Margin" user)
		(31 "F.CrtYd" user "Package Geometry/Place Bound Top")
		(29 "B.CrtYd" user "Package Geometry/Place Bound Bottom")
		(35 "F.Fab" user "Ref Des/Assembly Top")
		(33 "B.Fab" user "Ref Des/Assembly Bottom")
	)
	(footprint ""
		(layer "F.Cu")
		(at 383.345182 -75.137518 90)
		(property "Reference" "R7E2"
			(at 0 0 90)
			(layer "F.SilkS")
			(hide yes)
			(effects
				(font
					(size 1.27 1.27)
				)
			)
		)
		(property "Value" ""
			(at 0 0 90)
			(layer "F.Fab")
			(effects
				(font
					(size 1.27 1.27)
				)
			)
		)
		(duplicate_pad_numbers_are_jumpers no)
		(fp_poly
			(pts
				(xy -0.2794 -0.1016) (xy 0.2794 -0.1016) (xy 0.2794 0.9906) (xy -0.2794 0.9906)
			)
			(stroke
				(width 0)
				(type default)
			)
			(fill no)
			(layer "F.CrtYd")
		)
		(fp_line
			(start 0.2794 -0.1016)
			(end -0.2794 -0.1016)
			(stroke
				(width 0.1)
				(type default)
			)
			(layer "F.Fab")
		)
		(fp_line
			(start -0.2794 -0.1016)
			(end -0.2794 0.9906)
			(stroke
				(width 0.1)
				(type default)
			)
			(layer "F.Fab")
		)
		(fp_line
			(start 0.2794 0.9906)
			(end 0.2794 -0.1016)
			(stroke
				(width 0.1)
				(type default)
			)
			(layer "F.Fab")
		)
		(fp_line
			(start -0.2794 0.9906)
			(end 0.2794 0.9906)
			(stroke
				(width 0.1)
				(type default)
			)
			(layer "F.Fab")
		)
		(pad "1" smd rect
			(at 0 0 90)
			(size 0.508 0.508)
			(layers "F.Cu" "F.Mask" "F.Paste")
			(net "PVCCIO_CPU0")
		)
		(pad "2" smd rect
			(at 0 0.889 90)
			(size 0.508 0.508)
			(layers "F.Cu" "F.Mask" "F.Paste")
			(net "H_CPU0_THERMTRIP_G_N")
		)
		(zone
			(layer "F.Cu")
			(hatch none 0.5)
			(connect_pads
				(clearance 0)
			)
			(min_thickness 0.25)
			(keepout
				(tracks allowed)
				(vias not_allowed)
				(pads allowed)
				(copperpour not_allowed)
				(footprints allowed)
			)
			(placement
				(enabled no)
				(sheetname "")
			)
			(fill
				(thermal_gap 0.5)
				(thermal_bridge_width 0.5)
				(island_removal_mode 0)
			)
			(polygon
				(pts
					(xy 383.599182 -74.883518) (xy 383.599182 -75.391518) (xy 383.980182 -75.391518) (xy 383.980182 -74.883518)
				)
			)
		)
		(zone
			(layer "F.Cu")
			(hatch none 0.5)
			(connect_pads
				(clearance 0)
			)
			(min_thickness 0.25)
			(keepout
				(tracks not_allowed)
				(vias allowed)
				(pads allowed)
				(copperpour not_allowed)
				(footprints allowed)
			)
			(placement
				(enabled no)
				(sheetname "")
			)
			(fill
				(thermal_gap 0.5)
				(thermal_bridge_width 0.5)
				(island_removal_mode 0)
			)
			(polygon
				(pts
					(xy 383.980182 -74.883518) (xy 383.980182 -75.391518) (xy 383.599182 -75.391518) (xy 383.599182 -74.883518)
				)
			)
		)
	)
	(footprint ""
		(layer "F.Cu")
		(at 268.50721 -84.890102)
		(property "Reference" "C5D1"
			(at 0 0 0)
			(layer "F.SilkS")
			(hide yes)
			(effects
				(font
					(size 1.27 1.27)
				)
			)
		)
		(property "Value" ""
			(at 0 0 0)
			(layer "F.Fab")
			(effects
				(font
					(size 1.27 1.27)
				)
			)
		)
		(duplicate_pad_numbers_are_jumpers no)
		(fp_poly
			(pts
				(xy -0.4953 -0.2032) (xy 0.4953 -0.2032) (xy 0.4953 1.6002) (xy -0.4953 1.6002)
			)
			(stroke
				(width 0)
				(type default)
			)
			(fill no)
			(layer "F.CrtYd")
		)
		(fp_line
			(start -0.4953 -0.2032)
			(end 0.4953 -0.2032)
			(stroke
				(width 0.1)
				(type default)
			)
			(layer "F.Fab")
		)
		(fp_line
			(start -0.4953 1.6002)
			(end -0.4953 -0.2032)
			(stroke
				(width 0.1)
				(type default)
			)
			(layer "F.Fab")
		)
		(fp_line
			(start 0.4953 -0.2032)
			(end 0.4953 1.6002)
			(stroke
				(width 0.1)
				(type default)
			)
			(layer "F.Fab")
		)
		(fp_line
			(start 0.4953 1.6002)
			(end -0.4953 1.6002)
			(stroke
				(width 0.1)
				(type default)
			)
			(layer "F.Fab")
		)
		(pad "1" smd rect
			(at 0 0)
			(size 0.762 0.889)
			(layers "F.Cu" "F.Mask" "F.Paste")
			(net "PVDDQ_DEF")
		)
		(pad "2" smd rect
			(at 0 1.397)
			(size 0.762 0.889)
			(layers "F.Cu" "F.Mask" "F.Paste")
			(net "GND")
		)
		(zone
			(layer "F.Cu")
			(hatch none 0.5)
			(connect_pads
				(clearance 0)
			)
			(min_thickness 0.25)
			(keepout
				(tracks not_allowed)
				(vias allowed)
				(pads allowed)
				(copperpour not_allowed)
				(footprints allowed)
			)
			(placement
				(enabled no)
				(sheetname "")
			)
			(fill
				(thermal_gap 0.5)
				(thermal_bridge_width 0.5)
				(island_removal_mode 0)
			)
			(polygon
				(pts
					(xy 268.12621 -84.445602) (xy 268.88821 -84.445602) (xy 268.88821 -83.937602) (xy 268.12621 -83.937602)
				)
			)
		)
	)
	(footprint ""
		(layer "F.Cu")
		(at 403.988016 -152.703784 90)
		(property "Reference" "C8A4"
			(at 0 0 90)
			(layer "F.SilkS")
			(hide yes)
			(effects
				(font
					(size 1.27 1.27)
				)
			)
		)
		(property "Value" ""
			(at 0 0 90)
			(layer "F.Fab")
			(effects
				(font
					(size 1.27 1.27)
				)
			)
		)
		(duplicate_pad_numbers_are_jumpers no)
		(fp_poly
			(pts
				(xy -0.4953 -0.2032) (xy 0.4953 -0.2032) (xy 0.4953 1.6002) (xy -0.4953 1.6002)
			)
			(stroke
				(width 0)
				(type default)
			)
			(fill no)
			(layer "F.CrtYd")
		)
		(fp_line
			(start 0.4953 -0.2032)
			(end 0.4953 1.6002)
			(stroke
				(width 0.1)
				(type default)
			)
			(layer "F.Fab")
		)
		(fp_line
			(start -0.4953 -0.2032)
			(end 0.4953 -0.2032)
			(stroke
				(width 0.1)
				(type default)
			)
			(layer "F.Fab")
		)
		(fp_line
			(start 0.4953 1.6002)
			(end -0.4953 1.6002)
			(stroke
				(width 0.1)
				(type default)
			)
			(layer "F.Fab")
		)
		(fp_line
			(start -0.4953 1.6002)
			(end -0.4953 -0.2032)
			(stroke
				(width 0.1)
				(type default)
			)
			(layer "F.Fab")
		)
		(pad "1" smd rect
			(at 0 0 90)
			(size 0.762 0.889)
			(layers "F.Cu" "F.Mask" "F.Paste")
			(net "P3V3_STBY")
		)
		(pad "2" smd rect
			(at 0 1.397 90)
			(size 0.762 0.889)
			(layers "F.Cu" "F.Mask" "F.Paste")
			(net "GND")
		)
		(zone
			(layer "F.Cu")
			(hatch none 0.5)
			(connect_pads
				(clearance 0)
			)
			(min_thickness 0.25)
			(keepout
				(tracks not_allowed)
				(vias allowed)
				(pads allowed)
				(copperpour not_allowed)
				(footprints allowed)
			)
			(placement
				(enabled no)
				(sheetname "")
			)
			(fill
				(thermal_gap 0.5)
				(thermal_bridge_width 0.5)
				(island_removal_mode 0)
			)
			(polygon
				(pts
					(xy 404.432516 -152.322784) (xy 404.432516 -153.084784) (xy 404.940516 -153.084784) (xy 404.940516 -152.322784)
				)
			)
		)
	)
)
